FILE_TYPE = CONNECTIVITY;
{Allegro Design Entry HDL 16.6-p007 (v16-6-112F) 10/10/2012}
"PAGE_NUMBER" = 27;
0"NC";
1"M_E_DQS_DP<17:0>";
2"M_E_DQS_DN<17:0>";
3"M_E_MA<17:0>";
4"M_E_BA<1:0>";
5"M_E_BG<1:0>";
6"M_E_CKE<3:0>";
7"M_E_CS_N<7:0>";
8"M_E_ODT<3:0>";
9"M_E_DQ<63:0>";
10"M_E_CLK_DN<3:0>";
11"M_E_CLK_DP<3:0>";
12"M_E_ECC<7:0>";
13"M_E_DQ<5>";
14"M_E_C<2>";
15"M_E_ECC<0>";
16"M_E_ECC<1>";
17"M_E_ECC<2>";
18"M_E_ECC<3>";
19"M_E_ECC<4>";
20"M_E_ECC<5>";
21"M_E_ECC<6>";
22"M_E_ECC<7>";
23"M_E_DQ<0>";
24"M_E_DQ<1>";
25"M_E_DQ<2>";
26"M_E_DQ<3>";
27"M_E_DQ<4>";
28"M_E_DQ<6>";
29"M_E_DQ<7>";
30"M_E_DQ<8>";
31"M_E_DQ<9>";
32"M_E_DQ<10>";
33"M_E_CLK_DP<0>";
34"M_E_CLK_DP<1>";
35"M_E_CLK_DP<2>";
36"M_E_CLK_DP<3>";
37"M_E_CLK_DN<0>";
38"M_E_CLK_DN<1>";
39"M_E_CLK_DN<2>";
40"M_E_CLK_DN<3>";
41"M_E_DQ<11>";
42"M_E_DQ<12>";
43"M_E_DQ<13>";
44"M_E_DQ<14>";
45"M_E_DQ<15>";
46"M_E_DQ<16>";
47"M_E_DQ<17>";
48"M_E_DQ<18>";
49"M_E_DQ<19>";
50"M_E_DQ<20>";
51"M_E_DQ<21>";
52"M_E_DQ<22>";
53"M_E_DQ<23>";
54"M_E_DQ<24>";
55"M_E_DQ<25>";
56"M_E_DQ<26>";
57"M_E_DQ<27>";
58"M_E_DQ<28>";
59"M_E_DQ<29>";
60"M_E_DQ<30>";
61"M_E_DQ<31>";
62"M_E_DQ<32>";
63"M_E_DQ<33>";
64"M_E_DQ<34>";
65"M_E_DQ<35>";
66"M_E_DQ<36>";
67"M_E_DQ<37>";
68"M_E_DQ<38>";
69"M_E_DQ<39>";
70"M_E_DQ<40>";
71"M_E_DQ<41>";
72"M_E_DQ<42>";
73"M_E_DQ<43>";
74"M_E_DQ<44>";
75"M_E_DQ<45>";
76"M_E_DQ<46>";
77"M_E_DQ<47>";
78"M_E_DQ<48>";
79"M_E_DQ<49>";
80"M_E_DQ<50>";
81"M_E_DQ<51>";
82"M_E_DQ<52>";
83"M_E_DQ<53>";
84"M_E_DQ<54>";
85"M_E_DQ<55>";
86"M_E_DQ<56>";
87"M_E_DQ<57>";
88"M_E_DQ<58>";
89"M_E_DQ<59>";
90"M_E_DQ<60>";
91"M_E_DQ<61>";
92"M_E_DQ<62>";
93"M_E_DQ<63>";
94"M_E_ODT<0>";
95"M_E_ODT<1>";
96"M_E_ODT<2>";
97"M_E_ODT<3>";
98"M_E_MA<0>";
99"M_E_MA<1>";
100"M_E_MA<2>";
101"M_E_CS_N<0>";
102"M_E_CS_N<1>";
103"M_E_CS_N<2>";
104"M_E_CS_N<3>";
105"M_E_CS_N<4>";
106"M_E_CS_N<5>";
107"M_E_CS_N<6>";
108"M_E_CS_N<7>";
109"M_E_CKE<0>";
110"M_E_CKE<1>";
111"M_E_CKE<2>";
112"M_E_CKE<3>";
113"M_E_BG<0>";
114"M_E_BG<1>";
115"M_E_BA<0>";
116"M_E_BA<1>";
117"M_E_ALERT_N";
118"M_E_PAR";
119"M_E_ACT_N";
120"M_E_MA<3>";
121"M_E_MA<4>";
122"M_E_MA<5>";
123"M_E_MA<6>";
124"M_E_MA<7>";
125"M_E_MA<8>";
126"M_E_MA<9>";
127"M_E_MA<10>";
128"M_E_MA<11>";
129"M_E_MA<12>";
130"M_E_MA<13>";
131"M_E_MA<14>";
132"M_E_MA<15>";
133"M_E_MA<16>";
134"M_E_MA<17>";
135"M_E_DQS_DP<0>";
136"M_E_DQS_DP<1>";
137"M_E_DQS_DP<2>";
138"M_E_DQS_DP<3>";
139"M_E_DQS_DP<4>";
140"M_E_DQS_DP<5>";
141"M_E_DQS_DN<0>";
142"M_E_DQS_DN<1>";
143"M_E_DQS_DN<2>";
144"M_E_DQS_DN<3>";
145"M_E_DQS_DN<4>";
146"M_E_DQS_DN<5>";
147"M_E_DQS_DN<6>";
148"M_E_DQS_DN<7>";
149"M_E_DQS_DN<8>";
150"M_E_DQS_DN<9>";
151"M_E_DQS_DN<10>";
152"M_E_DQS_DN<11>";
153"M_E_DQS_DN<12>";
154"M_E_DQS_DN<13>";
155"M_E_DQS_DN<14>";
156"M_E_DQS_DN<15>";
157"M_E_DQS_DN<16>";
158"M_E_DQS_DN<17>";
159"M_E_DQS_DP<6>";
160"M_E_DQS_DP<7>";
161"M_E_DQS_DP<8>";
162"M_E_DQS_DP<9>";
163"M_E_DQS_DP<10>";
164"M_E_DQS_DP<11>";
165"M_E_DQS_DP<12>";
166"M_E_DQS_DP<13>";
167"M_E_DQS_DP<14>";
168"M_E_DQS_DP<15>";
169"M_E_DQS_DP<16>";
170"M_E_DQS_DP<17>";
%"TAP"
"6","(-5575,850)","0","mstr_standard","I10";
;
HDL_TAP"TRUE"
BODY_TYPE"PLUMBING"
CDS_LIB"mstr_standard";
"B \NAC \NWC"11;
"S \NAC"
BN"1"34;
%"TAP"
"6","(-2850,1400)","2","mstr_standard","I100";
;
HDL_TAP"TRUE"
BODY_TYPE"PLUMBING"
CDS_LIB"mstr_standard";
"B \NAC \NWC"8;
"S \NAC"
BN"0"94;
%"TAP"
"6","(-2850,1550)","2","mstr_standard","I101";
;
HDL_TAP"TRUE"
BODY_TYPE"PLUMBING"
CDS_LIB"mstr_standard";
"B \NAC \NWC"8;
"S \NAC"
BN"3"97;
%"TAP"
"6","(-2850,1500)","2","mstr_standard","I102";
;
HDL_TAP"TRUE"
BODY_TYPE"PLUMBING"
CDS_LIB"mstr_standard";
"B \NAC \NWC"8;
"S \NAC"
BN"2"96;
%"TAP"
"6","(-2850,1650)","2","mstr_standard","I103";
;
HDL_TAP"TRUE"
BODY_TYPE"PLUMBING"
CDS_LIB"mstr_standard";
"B \NAC \NWC"6;
"S \NAC"
BN"0"109;
%"TAP"
"6","(-2850,1700)","2","mstr_standard","I104";
;
HDL_TAP"TRUE"
BODY_TYPE"PLUMBING"
CDS_LIB"mstr_standard";
"B \NAC \NWC"6;
"S \NAC"
BN"1"110;
%"TAP"
"6","(-2850,1800)","2","mstr_standard","I105";
;
HDL_TAP"TRUE"
BODY_TYPE"PLUMBING"
CDS_LIB"mstr_standard";
"B \NAC \NWC"6;
"S \NAC"
BN"3"112;
%"TAP"
"6","(-2850,1750)","2","mstr_standard","I106";
;
HDL_TAP"TRUE"
BODY_TYPE"PLUMBING"
CDS_LIB"mstr_standard";
"B \NAC \NWC"6;
"S \NAC"
BN"2"111;
%"TAP"
"6","(-2850,1900)","2","mstr_standard","I107";
;
HDL_TAP"TRUE"
BODY_TYPE"PLUMBING"
CDS_LIB"mstr_standard";
"B \NAC \NWC"3;
"S \NAC"
BN"0"98;
%"TAP"
"6","(-2850,1950)","2","mstr_standard","I108";
;
HDL_TAP"TRUE"
BODY_TYPE"PLUMBING"
CDS_LIB"mstr_standard";
"B \NAC \NWC"3;
"S \NAC"
BN"1"99;
%"TAP"
"6","(-2850,2050)","2","mstr_standard","I109";
;
HDL_TAP"TRUE"
BODY_TYPE"PLUMBING"
CDS_LIB"mstr_standard";
"B \NAC \NWC"3;
"S \NAC"
BN"3"120;
%"TAP"
"6","(-5575,900)","0","mstr_standard","I11";
;
HDL_TAP"TRUE"
BODY_TYPE"PLUMBING"
CDS_LIB"mstr_standard";
"B \NAC \NWC"11;
"S \NAC"
BN"2"35;
%"TAP"
"6","(-2850,2000)","2","mstr_standard","I110";
;
HDL_TAP"TRUE"
BODY_TYPE"PLUMBING"
CDS_LIB"mstr_standard";
"B \NAC \NWC"3;
"S \NAC"
BN"2"100;
%"TAP"
"6","(-2850,2100)","2","mstr_standard","I111";
;
HDL_TAP"TRUE"
BODY_TYPE"PLUMBING"
CDS_LIB"mstr_standard";
"B \NAC \NWC"3;
"S \NAC"
BN"4"121;
%"TAP"
"6","(-2850,2150)","2","mstr_standard","I112";
;
HDL_TAP"TRUE"
BODY_TYPE"PLUMBING"
CDS_LIB"mstr_standard";
"B \NAC \NWC"3;
"S \NAC"
BN"5"122;
%"TAP"
"6","(-2850,2200)","2","mstr_standard","I113";
;
HDL_TAP"TRUE"
BODY_TYPE"PLUMBING"
CDS_LIB"mstr_standard";
"B \NAC \NWC"3;
"S \NAC"
BN"6"123;
%"TAP"
"6","(-2850,2350)","2","mstr_standard","I114";
;
HDL_TAP"TRUE"
BODY_TYPE"PLUMBING"
CDS_LIB"mstr_standard";
"B \NAC \NWC"3;
"S \NAC"
BN"9"126;
%"TAP"
"6","(-2850,2300)","2","mstr_standard","I115";
;
HDL_TAP"TRUE"
BODY_TYPE"PLUMBING"
CDS_LIB"mstr_standard";
"B \NAC \NWC"3;
"S \NAC"
BN"8"125;
%"TAP"
"6","(-2850,2250)","2","mstr_standard","I116";
;
HDL_TAP"TRUE"
BODY_TYPE"PLUMBING"
CDS_LIB"mstr_standard";
"B \NAC \NWC"3;
"S \NAC"
BN"7"124;
%"TAP"
"6","(-2850,2450)","2","mstr_standard","I117";
;
HDL_TAP"TRUE"
BODY_TYPE"PLUMBING"
CDS_LIB"mstr_standard";
"B \NAC \NWC"3;
"S \NAC"
BN"11"128;
%"TAP"
"6","(-2850,2400)","2","mstr_standard","I118";
;
HDL_TAP"TRUE"
BODY_TYPE"PLUMBING"
CDS_LIB"mstr_standard";
"B \NAC \NWC"3;
"S \NAC"
BN"10"127;
%"TAP"
"6","(-2850,2500)","2","mstr_standard","I119";
;
HDL_TAP"TRUE"
BODY_TYPE"PLUMBING"
CDS_LIB"mstr_standard";
"B \NAC \NWC"3;
"S \NAC"
BN"12"129;
%"TAP"
"6","(-5575,950)","0","mstr_standard","I12";
;
HDL_TAP"TRUE"
BODY_TYPE"PLUMBING"
CDS_LIB"mstr_standard";
"B \NAC \NWC"11;
"S \NAC"
BN"3"36;
%"TAP"
"6","(-2850,2550)","2","mstr_standard","I120";
;
HDL_TAP"TRUE"
BODY_TYPE"PLUMBING"
CDS_LIB"mstr_standard";
"B \NAC \NWC"3;
"S \NAC"
BN"13"130;
%"TAP"
"6","(-2850,2600)","2","mstr_standard","I121";
;
HDL_TAP"TRUE"
BODY_TYPE"PLUMBING"
CDS_LIB"mstr_standard";
"B \NAC \NWC"3;
"S \NAC"
BN"14"131;
%"TAP"
"6","(-2850,2700)","2","mstr_standard","I122";
;
HDL_TAP"TRUE"
BODY_TYPE"PLUMBING"
CDS_LIB"mstr_standard";
"B \NAC \NWC"3;
"S \NAC"
BN"16"133;
%"TAP"
"6","(-2850,2650)","2","mstr_standard","I123";
;
HDL_TAP"TRUE"
BODY_TYPE"PLUMBING"
CDS_LIB"mstr_standard";
"B \NAC \NWC"3;
"S \NAC"
BN"15"132;
%"TAP"
"6","(-2850,2750)","2","mstr_standard","I124";
;
HDL_TAP"TRUE"
BODY_TYPE"PLUMBING"
CDS_LIB"mstr_standard";
"B \NAC \NWC"3;
"S \NAC"
BN"17"134;
%"TAP"
"6","(-2850,2850)","2","mstr_standard","I125";
;
HDL_TAP"TRUE"
BODY_TYPE"PLUMBING"
CDS_LIB"mstr_standard";
"B \NAC \NWC"2;
"S \NAC"
BN"0"141;
%"TAP"
"6","(-2850,2950)","2","mstr_standard","I126";
;
HDL_TAP"TRUE"
BODY_TYPE"PLUMBING"
CDS_LIB"mstr_standard";
"B \NAC \NWC"2;
"S \NAC"
BN"2"143;
%"TAP"
"6","(-2850,2900)","2","mstr_standard","I127";
;
HDL_TAP"TRUE"
BODY_TYPE"PLUMBING"
CDS_LIB"mstr_standard";
"B \NAC \NWC"2;
"S \NAC"
BN"1"142;
%"TAP"
"6","(-2850,3000)","2","mstr_standard","I128";
;
HDL_TAP"TRUE"
BODY_TYPE"PLUMBING"
CDS_LIB"mstr_standard";
"B \NAC \NWC"2;
"S \NAC"
BN"3"144;
%"TAP"
"6","(-2850,3050)","2","mstr_standard","I129";
;
HDL_TAP"TRUE"
BODY_TYPE"PLUMBING"
CDS_LIB"mstr_standard";
"B \NAC \NWC"2;
"S \NAC"
BN"4"145;
%"TAP"
"6","(-5575,1050)","0","mstr_standard","I13";
;
HDL_TAP"TRUE"
BODY_TYPE"PLUMBING"
CDS_LIB"mstr_standard";
"B \NAC \NWC"12;
"S \NAC"
BN"0"15;
%"TAP"
"6","(-2850,3100)","2","mstr_standard","I130";
;
HDL_TAP"TRUE"
BODY_TYPE"PLUMBING"
CDS_LIB"mstr_standard";
"B \NAC \NWC"2;
"S \NAC"
BN"5"146;
%"TAP"
"6","(-2850,3200)","2","mstr_standard","I131";
;
HDL_TAP"TRUE"
BODY_TYPE"PLUMBING"
CDS_LIB"mstr_standard";
"B \NAC \NWC"2;
"S \NAC"
BN"7"148;
%"TAP"
"6","(-2850,3150)","2","mstr_standard","I132";
;
HDL_TAP"TRUE"
BODY_TYPE"PLUMBING"
CDS_LIB"mstr_standard";
"B \NAC \NWC"2;
"S \NAC"
BN"6"147;
%"TAP"
"6","(-2850,3250)","2","mstr_standard","I133";
;
HDL_TAP"TRUE"
BODY_TYPE"PLUMBING"
CDS_LIB"mstr_standard";
"B \NAC \NWC"2;
"S \NAC"
BN"8"149;
%"TAP"
"6","(-2850,3350)","2","mstr_standard","I134";
;
HDL_TAP"TRUE"
BODY_TYPE"PLUMBING"
CDS_LIB"mstr_standard";
"B \NAC \NWC"2;
"S \NAC"
BN"10"151;
%"TAP"
"6","(-2850,3300)","2","mstr_standard","I135";
;
HDL_TAP"TRUE"
BODY_TYPE"PLUMBING"
CDS_LIB"mstr_standard";
"B \NAC \NWC"2;
"S \NAC"
BN"9"150;
%"TAP"
"6","(-2850,3500)","2","mstr_standard","I136";
;
HDL_TAP"TRUE"
BODY_TYPE"PLUMBING"
CDS_LIB"mstr_standard";
"B \NAC \NWC"2;
"S \NAC"
BN"13"154;
%"TAP"
"6","(-2850,3400)","2","mstr_standard","I137";
;
HDL_TAP"TRUE"
BODY_TYPE"PLUMBING"
CDS_LIB"mstr_standard";
"B \NAC \NWC"2;
"S \NAC"
BN"11"152;
%"TAP"
"6","(-2850,3450)","2","mstr_standard","I138";
;
HDL_TAP"TRUE"
BODY_TYPE"PLUMBING"
CDS_LIB"mstr_standard";
"B \NAC \NWC"2;
"S \NAC"
BN"12"153;
%"TAP"
"6","(-2850,3600)","2","mstr_standard","I139";
;
HDL_TAP"TRUE"
BODY_TYPE"PLUMBING"
CDS_LIB"mstr_standard";
"B \NAC \NWC"2;
"S \NAC"
BN"15"156;
%"TAP"
"6","(-5575,1100)","0","mstr_standard","I14";
;
HDL_TAP"TRUE"
BODY_TYPE"PLUMBING"
CDS_LIB"mstr_standard";
"B \NAC \NWC"12;
"S \NAC"
BN"1"16;
%"TAP"
"6","(-2850,3550)","2","mstr_standard","I140";
;
HDL_TAP"TRUE"
BODY_TYPE"PLUMBING"
CDS_LIB"mstr_standard";
"B \NAC \NWC"2;
"S \NAC"
BN"14"155;
%"TAP"
"6","(-2850,3700)","2","mstr_standard","I141";
;
HDL_TAP"TRUE"
BODY_TYPE"PLUMBING"
CDS_LIB"mstr_standard";
"B \NAC \NWC"2;
"S \NAC"
BN"17"158;
%"TAP"
"6","(-2850,3650)","2","mstr_standard","I142";
;
HDL_TAP"TRUE"
BODY_TYPE"PLUMBING"
CDS_LIB"mstr_standard";
"B \NAC \NWC"2;
"S \NAC"
BN"16"157;
%"TAP"
"6","(-2850,3850)","2","mstr_standard","I143";
;
HDL_TAP"TRUE"
BODY_TYPE"PLUMBING"
CDS_LIB"mstr_standard";
"B \NAC \NWC"1;
"S \NAC"
BN"1"136;
%"TAP"
"6","(-2850,3800)","2","mstr_standard","I144";
;
HDL_TAP"TRUE"
BODY_TYPE"PLUMBING"
CDS_LIB"mstr_standard";
"B \NAC \NWC"1;
"S \NAC"
BN"0"135;
%"TAP"
"6","(-2850,4000)","2","mstr_standard","I145";
;
HDL_TAP"TRUE"
BODY_TYPE"PLUMBING"
CDS_LIB"mstr_standard";
"B \NAC \NWC"1;
"S \NAC"
BN"4"139;
%"TAP"
"6","(-2850,3950)","2","mstr_standard","I146";
;
HDL_TAP"TRUE"
BODY_TYPE"PLUMBING"
CDS_LIB"mstr_standard";
"B \NAC \NWC"1;
"S \NAC"
BN"3"138;
%"TAP"
"6","(-2850,3900)","2","mstr_standard","I147";
;
HDL_TAP"TRUE"
BODY_TYPE"PLUMBING"
CDS_LIB"mstr_standard";
"B \NAC \NWC"1;
"S \NAC"
BN"2"137;
%"TAP"
"6","(-5575,1150)","0","mstr_standard","I15";
;
HDL_TAP"TRUE"
BODY_TYPE"PLUMBING"
CDS_LIB"mstr_standard";
"B \NAC \NWC"12;
"S \NAC"
BN"2"17;
%"TAP"
"6","(-2850,4100)","2","mstr_standard","I158";
;
HDL_TAP"TRUE"
BODY_TYPE"PLUMBING"
CDS_LIB"mstr_standard";
"B \NAC \NWC"1;
"S \NAC"
BN"6"159;
%"TAP"
"6","(-2850,4050)","2","mstr_standard","I159";
;
HDL_TAP"TRUE"
BODY_TYPE"PLUMBING"
CDS_LIB"mstr_standard";
"B \NAC \NWC"1;
"S \NAC"
BN"5"140;
%"TAP"
"6","(-5575,1200)","0","mstr_standard","I16";
;
HDL_TAP"TRUE"
BODY_TYPE"PLUMBING"
CDS_LIB"mstr_standard";
"B \NAC \NWC"12;
"S \NAC"
BN"3"18;
%"TAP"
"6","(-2850,4150)","2","mstr_standard","I160";
;
HDL_TAP"TRUE"
BODY_TYPE"PLUMBING"
CDS_LIB"mstr_standard";
"B \NAC \NWC"1;
"S \NAC"
BN"7"160;
%"TAP"
"6","(-2850,4250)","2","mstr_standard","I161";
;
HDL_TAP"TRUE"
BODY_TYPE"PLUMBING"
CDS_LIB"mstr_standard";
"B \NAC \NWC"1;
"S \NAC"
BN"9"162;
%"TAP"
"6","(-2850,4200)","2","mstr_standard","I162";
;
HDL_TAP"TRUE"
BODY_TYPE"PLUMBING"
CDS_LIB"mstr_standard";
"B \NAC \NWC"1;
"S \NAC"
BN"8"161;
%"TAP"
"6","(-2850,4400)","2","mstr_standard","I163";
;
HDL_TAP"TRUE"
BODY_TYPE"PLUMBING"
CDS_LIB"mstr_standard";
"B \NAC \NWC"1;
"S \NAC"
BN"12"165;
%"TAP"
"6","(-2850,4350)","2","mstr_standard","I164";
;
HDL_TAP"TRUE"
BODY_TYPE"PLUMBING"
CDS_LIB"mstr_standard";
"B \NAC \NWC"1;
"S \NAC"
BN"11"164;
%"TAP"
"6","(-2850,4300)","2","mstr_standard","I165";
;
HDL_TAP"TRUE"
BODY_TYPE"PLUMBING"
CDS_LIB"mstr_standard";
"B \NAC \NWC"1;
"S \NAC"
BN"10"163;
%"TAP"
"6","(-2850,4450)","2","mstr_standard","I166";
;
HDL_TAP"TRUE"
BODY_TYPE"PLUMBING"
CDS_LIB"mstr_standard";
"B \NAC \NWC"1;
"S \NAC"
BN"13"166;
%"TAP"
"6","(-2850,4500)","2","mstr_standard","I167";
;
HDL_TAP"TRUE"
BODY_TYPE"PLUMBING"
CDS_LIB"mstr_standard";
"B \NAC \NWC"1;
"S \NAC"
BN"14"167;
%"TAP"
"6","(-2850,4550)","2","mstr_standard","I168";
;
HDL_TAP"TRUE"
BODY_TYPE"PLUMBING"
CDS_LIB"mstr_standard";
"B \NAC \NWC"1;
"S \NAC"
BN"15"168;
%"TAP"
"6","(-2850,4600)","2","mstr_standard","I169";
;
HDL_TAP"TRUE"
BODY_TYPE"PLUMBING"
CDS_LIB"mstr_standard";
"B \NAC \NWC"1;
"S \NAC"
BN"16"169;
%"TAP"
"6","(-5575,1250)","0","mstr_standard","I17";
;
HDL_TAP"TRUE"
BODY_TYPE"PLUMBING"
CDS_LIB"mstr_standard";
"B \NAC \NWC"12;
"S \NAC"
BN"4"19;
%"TAP"
"6","(-2850,4650)","2","mstr_standard","I170";
;
HDL_TAP"TRUE"
BODY_TYPE"PLUMBING"
CDS_LIB"mstr_standard";
"B \NAC \NWC"1;
"S \NAC"
BN"17"170;
%"SKX_EXT_B"
"7","(-4175,2550)","0","chpset_lib","I172";
;
CDS_SEC"7"
ROOM"CPU0"
CDS_LOCATION"U5D1"
SEC"7"
SEC_TYPE"BGA1"
CDS_LIB"chpset_lib"
PACK_TYPE"BGA1"
MATERIAL"IC"
PART_NUMBER"TBD"
LOCATION"U5D1";
"DDR4_PAR"
$PN"DV53"118;
"DDR4_ODT<0>"
$PN"DR50"94;
"DDR4_ODT<1>"
$PN"DN48"95;
"DDR4_ODT<2>"
$PN"DT49"96;
"DDR4_ODT<3>"
$PN"DM47"97;
"DDR4_MA<0>"
$PN"DW52"98;
"DDR4_MA<1>"
$PN"DW58"99;
"DDR4_MA<2>"
$PN"DV57"100;
"DDR4_MA<3>"
$PN"DR58"120;
"DDR4_MA<4>"
$PN"DT59"121;
"DDR4_MA<5>"
$PN"DN58"122;
"DDR4_MA<6>"
$PN"DM59"123;
"DDR4_MA<7>"
$PN"DK61"124;
"DDR4_MA<8>"
$PN"DJ60"125;
"DDR4_MA<9>"
$PN"DV59"126;
"DDR4_MA<10>"
$PN"DT55"127;
"DDR4_MA<11>"
$PN"DR60"128;
"DDR4_MA<12>"
$PN"DN60"129;
"DDR4_MA<13>"
$PN"DT51"130;
"DDR4_MA<14>"
$PN"DM51"131;
"DDR4_MA<15>"
$PN"DR52"132;
"DDR4_MA<16>"
$PN"DN52"133;
"DDR4_MA<17>"
$PN"DR48"134;
"DDR4_ECC<0>"
$PN"DY69"15;
"DDR4_ECC<1>"
$PN"EA68"16;
"DDR4_ECC<2>"
$PN"DV65"17;
"DDR4_ECC<3>"
$PN"DY65"18;
"DDR4_ECC<4>"
$PN"DU68"19;
"DDR4_ECC<5>"
$PN"DV69"20;
"DDR4_ECC<6>"
$PN"DU66"21;
"DDR4_ECC<7>"
$PN"EA66"22;
"DDR4_DQS_DP<0>"
$PN"CM81"135;
"DDR4_DQS_DP<1>"
$PN"DB81"136;
"DDR4_DQS_DP<2>"
$PN"EB79"137;
"DDR4_DQS_DP<3>"
$PN"ED73"138;
"DDR4_DQS_DP<4>"
$PN"DT41"139;
"DDR4_DQS_DP<5>"
$PN"EC32"140;
"DDR4_DQS_DP<6>"
$PN"EC26"159;
"DDR4_DQS_DP<7>"
$PN"DJ26"160;
"DDR4_DQS_DP<8>"
$PN"DY67"161;
"DDR4_DQS_DP<9>"
$PN"CP79"162;
"DDR4_DQS_DP<10>"
$PN"DD79"163;
"DDR4_DQS_DP<11>"
$PN"DV79"164;
"DDR4_DQS_DP<12>"
$PN"DY73"165;
"DDR4_DQS_DP<13>"
$PN"DM41"166;
"DDR4_DQS_DP<14>"
$PN"DW32"167;
"DDR4_DQS_DP<15>"
$PN"DW26"168;
"DDR4_DQS_DP<16>"
$PN"DE26"169;
"DDR4_DQS_DP<17>"
$PN"DT67"170;
"DDR4_DQS_DN<0>"
$PN"CL82"141;
"DDR4_DQS_DN<1>"
$PN"DA82"142;
"DDR4_DQS_DN<2>"
$PN"ED79"143;
"DDR4_DQS_DN<3>"
$PN"EF73"144;
"DDR4_DQS_DN<4>"
$PN"DV41"145;
"DDR4_DQS_DN<5>"
$PN"EE32"146;
"DDR4_DQS_DN<6>"
$PN"EE26"147;
"DDR4_DQS_DN<7>"
$PN"DL26"148;
"DDR4_DQS_DN<8>"
$PN"EB67"149;
"DDR4_DQS_DN<9>"
$PN"CN80"150;
"DDR4_DQS_DN<10>"
$PN"DC80"151;
"DDR4_DQS_DN<11>"
$PN"DY79"152;
"DDR4_DQS_DN<12>"
$PN"EB73"153;
"DDR4_DQS_DN<13>"
$PN"DP41"154;
"DDR4_DQS_DN<14>"
$PN"EA32"155;
"DDR4_DQS_DN<15>"
$PN"EA26"156;
"DDR4_DQS_DN<16>"
$PN"DG26"157;
"DDR4_DQS_DN<17>"
$PN"DV67"158;
"DDR4_DQ<0>"
$PN"CM79"23;
"DDR4_DQ<1>"
$PN"CK81"24;
"DDR4_DQ<2>"
$PN"CT81"25;
"DDR4_DQ<3>"
$PN"CR82"26;
"DDR4_DQ<4>"
$PN"CK79"27;
"DDR4_DQ<5>"
$PN"CJ80"13;
"DDR4_DQ<6>"
$PN"CR80"28;
"DDR4_DQ<7>"
$PN"CN82"29;
"DDR4_DQ<8>"
$PN"DB79"30;
"DDR4_DQ<9>"
$PN"CY81"31;
"DDR4_DQ<10>"
$PN"DE80"32;
"DDR4_DQ<11>"
$PN"DF81"41;
"DDR4_DQ<12>"
$PN"CY79"42;
"DDR4_DQ<13>"
$PN"CW80"43;
"DDR4_DQ<14>"
$PN"DC82"44;
"DDR4_DQ<15>"
$PN"DE82"45;
"DDR4_DQ<16>"
$PN"DW80"46;
"DDR4_DQ<17>"
$PN"EC80"47;
"DDR4_DQ<18>"
$PN"DY77"48;
"DDR4_DQ<19>"
$PN"EB77"49;
"DDR4_DQ<20>"
$PN"DY81"50;
"DDR4_DQ<21>"
$PN"EB81"51;
"DDR4_DQ<22>"
$PN"DW78"52;
"DDR4_DQ<23>"
$PN"EC78"53;
"DDR4_DQ<24>"
$PN"ED75"54;
"DDR4_DQ<25>"
$PN"EE74"55;
"DDR4_DQ<26>"
$PN"EB71"56;
"DDR4_DQ<27>"
$PN"ED71"57;
"DDR4_DQ<28>"
$PN"EA74"58;
"DDR4_DQ<29>"
$PN"EB75"59;
"DDR4_DQ<30>"
$PN"EA72"60;
"DDR4_DQ<31>"
$PN"EE72"61;
"DDR4_DQ<32>"
$PN"DU42"62;
"DDR4_DQ<33>"
$PN"DW42"63;
"DDR4_DQ<34>"
$PN"DP39"64;
"DDR4_DQ<35>"
$PN"DT39"65;
"DDR4_DQ<36>"
$PN"DL42"66;
"DDR4_DQ<37>"
$PN"DN42"67;
"DDR4_DQ<38>"
$PN"DN40"68;
"DDR4_DQ<39>"
$PN"DU40"69;
"DDR4_DQ<40>"
$PN"EC34"70;
"DDR4_DQ<41>"
$PN"ED33"71;
"DDR4_DQ<42>"
$PN"EA30"72;
"DDR4_DQ<43>"
$PN"EC30"73;
"DDR4_DQ<44>"
$PN"DY33"74;
"DDR4_DQ<45>"
$PN"EA34"75;
"DDR4_DQ<46>"
$PN"DY31"76;
"DDR4_DQ<47>"
$PN"ED31"77;
"DDR4_DQ<48>"
$PN"EC28"78;
"DDR4_DQ<49>"
$PN"ED27"79;
"DDR4_DQ<50>"
$PN"EA24"80;
"DDR4_DQ<51>"
$PN"EC24"81;
"DDR4_DQ<52>"
$PN"DY27"82;
"DDR4_DQ<53>"
$PN"EA28"83;
"DDR4_DQ<54>"
$PN"DY25"84;
"DDR4_DQ<55>"
$PN"ED25"85;
"DDR4_DQ<56>"
$PN"DF27"86;
"DDR4_DQ<57>"
$PN"DK27"87;
"DDR4_DQ<58>"
$PN"DD25"88;
"DDR4_DQ<59>"
$PN"DJ24"89;
"DDR4_DQ<60>"
$PN"DG28"90;
"DDR4_DQ<61>"
$PN"DJ28"91;
"DDR4_DQ<62>"
$PN"DF25"92;
"DDR4_DQ<63>"
$PN"DK25"93;
"DDR4_CS_N<0>"
$PN"DV51"101;
"DDR4_CS_N<1>"
$PN"DN50"102;
"DDR4_CS_N<2>"
$PN"DR46"103;
"DDR4_CS_N<3>"
$PN"DK47"104;
"DDR4_CS_N<4>"
$PN"DW50"105;
"DDR4_CS_N<5>"
$PN"DM49"106;
"DDR4_CS_N<6>"
$PN"DT45"107;
"DDR4_CS_N<7>"
$PN"DN46"108;
"DDR4_CLK_DP<0>"
$PN"DN54"33;
"DDR4_CLK_DP<1>"
$PN"DT53"34;
"DDR4_CLK_DP<2>"
$PN"DN56"35;
"DDR4_CLK_DP<3>"
$PN"DR56"36;
"DDR4_CLK_DN<0>"
$PN"DM55"37;
"DDR4_CLK_DN<1>"
$PN"DR54"38;
"DDR4_CLK_DN<2>"
$PN"DM57"39;
"DDR4_CLK_DN<3>"
$PN"DT57"40;
"DDR4_CKE<0>"
$PN"DM63"109;
"DDR4_CKE<1>"
$PN"DN64"110;
"DDR4_CKE<2>"
$PN"DL64"111;
"DDR4_CKE<3>"
$PN"DR64"112;
"DDR4_CID<2>"
$PN"DT47"14;
"DDR4_BG<0>"
$PN"DJ62"113;
"DDR4_BG<1>"
$PN"DM61"114;
"DDR4_BA<0>"
$PN"DM53"115;
"DDR4_BA<1>"
$PN"DV55"116;
"DDR4_ALERT_N"
$PN"DT61"117;
"DDR4_ACT_N"
$PN"DR62"119;
%"TAP"
"6","(-5575,1300)","0","mstr_standard","I18";
;
HDL_TAP"TRUE"
BODY_TYPE"PLUMBING"
CDS_LIB"mstr_standard";
"B \NAC \NWC"12;
"S \NAC"
BN"5"20;
%"TAP"
"6","(-5575,1350)","0","mstr_standard","I19";
;
HDL_TAP"TRUE"
BODY_TYPE"PLUMBING"
CDS_LIB"mstr_standard";
"B \NAC \NWC"12;
"S \NAC"
BN"6"21;
%"TAP"
"6","(-5575,1400)","0","mstr_standard","I20";
;
HDL_TAP"TRUE"
BODY_TYPE"PLUMBING"
CDS_LIB"mstr_standard";
"B \NAC \NWC"12;
"S \NAC"
BN"7"22;
%"TAP"
"6","(-5575,1550)","0","mstr_standard","I21";
;
HDL_TAP"TRUE"
BODY_TYPE"PLUMBING"
CDS_LIB"mstr_standard";
"B \NAC \NWC"9;
"S \NAC"
BN"1"24;
%"TAP"
"6","(-5575,1500)","0","mstr_standard","I22";
;
HDL_TAP"TRUE"
BODY_TYPE"PLUMBING"
CDS_LIB"mstr_standard";
"B \NAC \NWC"9;
"S \NAC"
BN"0"23;
%"TAP"
"6","(-5575,1600)","0","mstr_standard","I23";
;
HDL_TAP"TRUE"
BODY_TYPE"PLUMBING"
CDS_LIB"mstr_standard";
"B \NAC \NWC"9;
"S \NAC"
BN"2"25;
%"TAP"
"6","(-5575,1650)","0","mstr_standard","I24";
;
HDL_TAP"TRUE"
BODY_TYPE"PLUMBING"
CDS_LIB"mstr_standard";
"B \NAC \NWC"9;
"S \NAC"
BN"3"26;
%"TAP"
"6","(-5575,1700)","0","mstr_standard","I25";
;
HDL_TAP"TRUE"
BODY_TYPE"PLUMBING"
CDS_LIB"mstr_standard";
"B \NAC \NWC"9;
"S \NAC"
BN"4"27;
%"TAP"
"6","(-5575,1750)","0","mstr_standard","I26";
;
HDL_TAP"TRUE"
BODY_TYPE"PLUMBING"
CDS_LIB"mstr_standard";
"B \NAC \NWC"9;
"S \NAC"
BN"5"13;
%"TAP"
"6","(-5575,1800)","0","mstr_standard","I27";
;
HDL_TAP"TRUE"
BODY_TYPE"PLUMBING"
CDS_LIB"mstr_standard";
"B \NAC \NWC"9;
"S \NAC"
BN"6"28;
%"TAP"
"6","(-5575,1900)","0","mstr_standard","I28";
;
HDL_TAP"TRUE"
BODY_TYPE"PLUMBING"
CDS_LIB"mstr_standard";
"B \NAC \NWC"9;
"S \NAC"
BN"8"30;
%"TAP"
"6","(-5575,1850)","0","mstr_standard","I29";
;
HDL_TAP"TRUE"
BODY_TYPE"PLUMBING"
CDS_LIB"mstr_standard";
"B \NAC \NWC"9;
"S \NAC"
BN"7"29;
%"TAP"
"6","(-5575,1950)","0","mstr_standard","I30";
;
HDL_TAP"TRUE"
BODY_TYPE"PLUMBING"
CDS_LIB"mstr_standard";
"B \NAC \NWC"9;
"S \NAC"
BN"9"31;
%"TAP"
"6","(-5575,2000)","0","mstr_standard","I32";
;
HDL_TAP"TRUE"
BODY_TYPE"PLUMBING"
CDS_LIB"mstr_standard";
"B \NAC \NWC"9;
"S \NAC"
BN"10"32;
%"TAP"
"6","(-5575,2050)","0","mstr_standard","I33";
;
HDL_TAP"TRUE"
BODY_TYPE"PLUMBING"
CDS_LIB"mstr_standard";
"B \NAC \NWC"9;
"S \NAC"
BN"11"41;
%"TAP"
"6","(-5575,2100)","0","mstr_standard","I34";
;
HDL_TAP"TRUE"
BODY_TYPE"PLUMBING"
CDS_LIB"mstr_standard";
"B \NAC \NWC"9;
"S \NAC"
BN"12"42;
%"TAP"
"6","(-5575,2150)","0","mstr_standard","I35";
;
HDL_TAP"TRUE"
BODY_TYPE"PLUMBING"
CDS_LIB"mstr_standard";
"B \NAC \NWC"9;
"S \NAC"
BN"13"43;
%"TAP"
"6","(-5575,2200)","0","mstr_standard","I36";
;
HDL_TAP"TRUE"
BODY_TYPE"PLUMBING"
CDS_LIB"mstr_standard";
"B \NAC \NWC"9;
"S \NAC"
BN"14"44;
%"TAP"
"6","(-5575,2250)","0","mstr_standard","I37";
;
HDL_TAP"TRUE"
BODY_TYPE"PLUMBING"
CDS_LIB"mstr_standard";
"B \NAC \NWC"9;
"S \NAC"
BN"15"45;
%"TAP"
"6","(-5575,2300)","0","mstr_standard","I38";
;
HDL_TAP"TRUE"
BODY_TYPE"PLUMBING"
CDS_LIB"mstr_standard";
"B \NAC \NWC"9;
"S \NAC"
BN"16"46;
%"TAP"
"6","(-5575,2350)","0","mstr_standard","I39";
;
HDL_TAP"TRUE"
BODY_TYPE"PLUMBING"
CDS_LIB"mstr_standard";
"B \NAC \NWC"9;
"S \NAC"
BN"17"47;
%"TAP"
"6","(-5575,2400)","0","mstr_standard","I40";
;
HDL_TAP"TRUE"
BODY_TYPE"PLUMBING"
CDS_LIB"mstr_standard";
"B \NAC \NWC"9;
"S \NAC"
BN"18"48;
%"TAP"
"6","(-5575,2450)","0","mstr_standard","I41";
;
HDL_TAP"TRUE"
BODY_TYPE"PLUMBING"
CDS_LIB"mstr_standard";
"B \NAC \NWC"9;
"S \NAC"
BN"19"49;
%"TAP"
"6","(-5575,2500)","0","mstr_standard","I42";
;
HDL_TAP"TRUE"
BODY_TYPE"PLUMBING"
CDS_LIB"mstr_standard";
"B \NAC \NWC"9;
"S \NAC"
BN"20"50;
%"TAP"
"6","(-5575,2550)","0","mstr_standard","I43";
;
HDL_TAP"TRUE"
BODY_TYPE"PLUMBING"
CDS_LIB"mstr_standard";
"B \NAC \NWC"9;
"S \NAC"
BN"21"51;
%"TAP"
"6","(-5575,2600)","0","mstr_standard","I44";
;
HDL_TAP"TRUE"
BODY_TYPE"PLUMBING"
CDS_LIB"mstr_standard";
"B \NAC \NWC"9;
"S \NAC"
BN"22"52;
%"TAP"
"6","(-5575,2650)","0","mstr_standard","I45";
;
HDL_TAP"TRUE"
BODY_TYPE"PLUMBING"
CDS_LIB"mstr_standard";
"B \NAC \NWC"9;
"S \NAC"
BN"23"53;
%"TAP"
"6","(-5575,2700)","0","mstr_standard","I46";
;
HDL_TAP"TRUE"
BODY_TYPE"PLUMBING"
CDS_LIB"mstr_standard";
"B \NAC \NWC"9;
"S \NAC"
BN"24"54;
%"TAP"
"6","(-5575,2800)","0","mstr_standard","I47";
;
HDL_TAP"TRUE"
BODY_TYPE"PLUMBING"
CDS_LIB"mstr_standard";
"B \NAC \NWC"9;
"S \NAC"
BN"26"56;
%"TAP"
"6","(-5575,2750)","0","mstr_standard","I48";
;
HDL_TAP"TRUE"
BODY_TYPE"PLUMBING"
CDS_LIB"mstr_standard";
"B \NAC \NWC"9;
"S \NAC"
BN"25"55;
%"TAP"
"6","(-5575,2850)","0","mstr_standard","I49";
;
HDL_TAP"TRUE"
BODY_TYPE"PLUMBING"
CDS_LIB"mstr_standard";
"B \NAC \NWC"9;
"S \NAC"
BN"27"57;
%"TAP"
"6","(-5575,600)","0","mstr_standard","I5";
;
HDL_TAP"TRUE"
BODY_TYPE"PLUMBING"
CDS_LIB"mstr_standard";
"B \NAC \NWC"10;
"S \NAC"
BN"0"37;
%"TAP"
"6","(-5575,2900)","0","mstr_standard","I50";
;
HDL_TAP"TRUE"
BODY_TYPE"PLUMBING"
CDS_LIB"mstr_standard";
"B \NAC \NWC"9;
"S \NAC"
BN"28"58;
%"TAP"
"6","(-5575,2950)","0","mstr_standard","I51";
;
HDL_TAP"TRUE"
BODY_TYPE"PLUMBING"
CDS_LIB"mstr_standard";
"B \NAC \NWC"9;
"S \NAC"
BN"29"59;
%"TAP"
"6","(-5575,3050)","0","mstr_standard","I52";
;
HDL_TAP"TRUE"
BODY_TYPE"PLUMBING"
CDS_LIB"mstr_standard";
"B \NAC \NWC"9;
"S \NAC"
BN"31"61;
%"TAP"
"6","(-5575,3000)","0","mstr_standard","I53";
;
HDL_TAP"TRUE"
BODY_TYPE"PLUMBING"
CDS_LIB"mstr_standard";
"B \NAC \NWC"9;
"S \NAC"
BN"30"60;
%"TAP"
"6","(-5575,3100)","0","mstr_standard","I54";
;
HDL_TAP"TRUE"
BODY_TYPE"PLUMBING"
CDS_LIB"mstr_standard";
"B \NAC \NWC"9;
"S \NAC"
BN"32"62;
%"TAP"
"6","(-5575,3150)","0","mstr_standard","I55";
;
HDL_TAP"TRUE"
BODY_TYPE"PLUMBING"
CDS_LIB"mstr_standard";
"B \NAC \NWC"9;
"S \NAC"
BN"33"63;
%"TAP"
"6","(-5575,3200)","0","mstr_standard","I56";
;
HDL_TAP"TRUE"
BODY_TYPE"PLUMBING"
CDS_LIB"mstr_standard";
"B \NAC \NWC"9;
"S \NAC"
BN"34"64;
%"TAP"
"6","(-5575,3250)","0","mstr_standard","I57";
;
HDL_TAP"TRUE"
BODY_TYPE"PLUMBING"
CDS_LIB"mstr_standard";
"B \NAC \NWC"9;
"S \NAC"
BN"35"65;
%"TAP"
"6","(-5575,3300)","0","mstr_standard","I58";
;
HDL_TAP"TRUE"
BODY_TYPE"PLUMBING"
CDS_LIB"mstr_standard";
"B \NAC \NWC"9;
"S \NAC"
BN"36"66;
%"TAP"
"6","(-5575,3350)","0","mstr_standard","I59";
;
HDL_TAP"TRUE"
BODY_TYPE"PLUMBING"
CDS_LIB"mstr_standard";
"B \NAC \NWC"9;
"S \NAC"
BN"37"67;
%"TAP"
"6","(-5575,650)","0","mstr_standard","I6";
;
HDL_TAP"TRUE"
BODY_TYPE"PLUMBING"
CDS_LIB"mstr_standard";
"B \NAC \NWC"10;
"S \NAC"
BN"1"38;
%"TAP"
"6","(-5575,3400)","0","mstr_standard","I60";
;
HDL_TAP"TRUE"
BODY_TYPE"PLUMBING"
CDS_LIB"mstr_standard";
"B \NAC \NWC"9;
"S \NAC"
BN"38"68;
%"TAP"
"6","(-5575,3450)","0","mstr_standard","I61";
;
HDL_TAP"TRUE"
BODY_TYPE"PLUMBING"
CDS_LIB"mstr_standard";
"B \NAC \NWC"9;
"S \NAC"
BN"39"69;
%"TAP"
"6","(-5575,3500)","0","mstr_standard","I62";
;
HDL_TAP"TRUE"
BODY_TYPE"PLUMBING"
CDS_LIB"mstr_standard";
"B \NAC \NWC"9;
"S \NAC"
BN"40"70;
%"TAP"
"6","(-5575,3550)","0","mstr_standard","I63";
;
HDL_TAP"TRUE"
BODY_TYPE"PLUMBING"
CDS_LIB"mstr_standard";
"B \NAC \NWC"9;
"S \NAC"
BN"41"71;
%"TAP"
"6","(-5575,3600)","0","mstr_standard","I64";
;
HDL_TAP"TRUE"
BODY_TYPE"PLUMBING"
CDS_LIB"mstr_standard";
"B \NAC \NWC"9;
"S \NAC"
BN"42"72;
%"TAP"
"6","(-5575,3650)","0","mstr_standard","I65";
;
HDL_TAP"TRUE"
BODY_TYPE"PLUMBING"
CDS_LIB"mstr_standard";
"B \NAC \NWC"9;
"S \NAC"
BN"43"73;
%"TAP"
"6","(-5575,3700)","0","mstr_standard","I66";
;
HDL_TAP"TRUE"
BODY_TYPE"PLUMBING"
CDS_LIB"mstr_standard";
"B \NAC \NWC"9;
"S \NAC"
BN"44"74;
%"TAP"
"6","(-5575,3750)","0","mstr_standard","I67";
;
HDL_TAP"TRUE"
BODY_TYPE"PLUMBING"
CDS_LIB"mstr_standard";
"B \NAC \NWC"9;
"S \NAC"
BN"45"75;
%"TAP"
"6","(-5575,3800)","0","mstr_standard","I68";
;
HDL_TAP"TRUE"
BODY_TYPE"PLUMBING"
CDS_LIB"mstr_standard";
"B \NAC \NWC"9;
"S \NAC"
BN"46"76;
%"TAP"
"6","(-5575,3850)","0","mstr_standard","I69";
;
HDL_TAP"TRUE"
BODY_TYPE"PLUMBING"
CDS_LIB"mstr_standard";
"B \NAC \NWC"9;
"S \NAC"
BN"47"77;
%"TAP"
"6","(-5575,750)","0","mstr_standard","I7";
;
HDL_TAP"TRUE"
BODY_TYPE"PLUMBING"
CDS_LIB"mstr_standard";
"B \NAC \NWC"10;
"S \NAC"
BN"3"40;
%"TAP"
"6","(-5575,3900)","0","mstr_standard","I70";
;
HDL_TAP"TRUE"
BODY_TYPE"PLUMBING"
CDS_LIB"mstr_standard";
"B \NAC \NWC"9;
"S \NAC"
BN"48"78;
%"TAP"
"6","(-5575,3950)","0","mstr_standard","I71";
;
HDL_TAP"TRUE"
BODY_TYPE"PLUMBING"
CDS_LIB"mstr_standard";
"B \NAC \NWC"9;
"S \NAC"
BN"49"79;
%"TAP"
"6","(-5575,4000)","0","mstr_standard","I72";
;
HDL_TAP"TRUE"
BODY_TYPE"PLUMBING"
CDS_LIB"mstr_standard";
"B \NAC \NWC"9;
"S \NAC"
BN"50"80;
%"TAP"
"6","(-5575,4050)","0","mstr_standard","I74";
;
HDL_TAP"TRUE"
BODY_TYPE"PLUMBING"
CDS_LIB"mstr_standard";
"B \NAC \NWC"9;
"S \NAC"
BN"51"81;
%"TAP"
"6","(-5575,4100)","0","mstr_standard","I75";
;
HDL_TAP"TRUE"
BODY_TYPE"PLUMBING"
CDS_LIB"mstr_standard";
"B \NAC \NWC"9;
"S \NAC"
BN"52"82;
%"TAP"
"6","(-5575,4150)","0","mstr_standard","I76";
;
HDL_TAP"TRUE"
BODY_TYPE"PLUMBING"
CDS_LIB"mstr_standard";
"B \NAC \NWC"9;
"S \NAC"
BN"53"83;
%"TAP"
"6","(-5575,4200)","0","mstr_standard","I77";
;
HDL_TAP"TRUE"
BODY_TYPE"PLUMBING"
CDS_LIB"mstr_standard";
"B \NAC \NWC"9;
"S \NAC"
BN"54"84;
%"TAP"
"6","(-5575,4250)","0","mstr_standard","I78";
;
HDL_TAP"TRUE"
BODY_TYPE"PLUMBING"
CDS_LIB"mstr_standard";
"B \NAC \NWC"9;
"S \NAC"
BN"55"85;
%"TAP"
"6","(-5575,4300)","0","mstr_standard","I79";
;
HDL_TAP"TRUE"
BODY_TYPE"PLUMBING"
CDS_LIB"mstr_standard";
"B \NAC \NWC"9;
"S \NAC"
BN"56"86;
%"TAP"
"6","(-5575,700)","0","mstr_standard","I8";
;
HDL_TAP"TRUE"
BODY_TYPE"PLUMBING"
CDS_LIB"mstr_standard";
"B \NAC \NWC"10;
"S \NAC"
BN"2"39;
%"TAP"
"6","(-5575,4350)","0","mstr_standard","I80";
;
HDL_TAP"TRUE"
BODY_TYPE"PLUMBING"
CDS_LIB"mstr_standard";
"B \NAC \NWC"9;
"S \NAC"
BN"57"87;
%"TAP"
"6","(-5575,4400)","0","mstr_standard","I81";
;
HDL_TAP"TRUE"
BODY_TYPE"PLUMBING"
CDS_LIB"mstr_standard";
"B \NAC \NWC"9;
"S \NAC"
BN"58"88;
%"TAP"
"6","(-5575,4450)","0","mstr_standard","I82";
;
HDL_TAP"TRUE"
BODY_TYPE"PLUMBING"
CDS_LIB"mstr_standard";
"B \NAC \NWC"9;
"S \NAC"
BN"59"89;
%"TAP"
"6","(-5575,4500)","0","mstr_standard","I83";
;
HDL_TAP"TRUE"
BODY_TYPE"PLUMBING"
CDS_LIB"mstr_standard";
"B \NAC \NWC"9;
"S \NAC"
BN"60"90;
%"TAP"
"6","(-5575,4550)","0","mstr_standard","I84";
;
HDL_TAP"TRUE"
BODY_TYPE"PLUMBING"
CDS_LIB"mstr_standard";
"B \NAC \NWC"9;
"S \NAC"
BN"61"91;
%"TAP"
"6","(-5575,4600)","0","mstr_standard","I85";
;
HDL_TAP"TRUE"
BODY_TYPE"PLUMBING"
CDS_LIB"mstr_standard";
"B \NAC \NWC"9;
"S \NAC"
BN"62"92;
%"TAP"
"6","(-5575,4650)","0","mstr_standard","I86";
;
HDL_TAP"TRUE"
BODY_TYPE"PLUMBING"
CDS_LIB"mstr_standard";
"B \NAC \NWC"9;
"S \NAC"
BN"63"93;
%"TAP"
"6","(-2850,800)","2","mstr_standard","I87";
;
HDL_TAP"TRUE"
BODY_TYPE"PLUMBING"
CDS_LIB"mstr_standard";
"B \NAC \NWC"5;
"S \NAC"
BN"0"113;
%"TAP"
"6","(-2850,750)","2","mstr_standard","I88";
;
HDL_TAP"TRUE"
BODY_TYPE"PLUMBING"
CDS_LIB"mstr_standard";
"B \NAC \NWC"4;
"S \NAC"
BN"1"116;
%"TAP"
"6","(-2850,700)","2","mstr_standard","I89";
;
HDL_TAP"TRUE"
BODY_TYPE"PLUMBING"
CDS_LIB"mstr_standard";
"B \NAC \NWC"4;
"S \NAC"
BN"0"115;
%"TAP"
"6","(-5575,800)","0","mstr_standard","I9";
;
HDL_TAP"TRUE"
BODY_TYPE"PLUMBING"
CDS_LIB"mstr_standard";
"B \NAC \NWC"11;
"S \NAC"
BN"0"33;
%"TAP"
"6","(-2850,850)","2","mstr_standard","I90";
;
HDL_TAP"TRUE"
BODY_TYPE"PLUMBING"
CDS_LIB"mstr_standard";
"B \NAC \NWC"5;
"S \NAC"
BN"1"114;
%"TAP"
"6","(-2850,1000)","2","mstr_standard","I91";
;
HDL_TAP"TRUE"
BODY_TYPE"PLUMBING"
CDS_LIB"mstr_standard";
"B \NAC \NWC"7;
"S \NAC"
BN"1"102;
%"TAP"
"6","(-2850,950)","2","mstr_standard","I92";
;
HDL_TAP"TRUE"
BODY_TYPE"PLUMBING"
CDS_LIB"mstr_standard";
"B \NAC \NWC"7;
"S \NAC"
BN"0"101;
%"TAP"
"6","(-2850,1050)","2","mstr_standard","I93";
;
HDL_TAP"TRUE"
BODY_TYPE"PLUMBING"
CDS_LIB"mstr_standard";
"B \NAC \NWC"7;
"S \NAC"
BN"2"103;
%"TAP"
"6","(-2850,1200)","2","mstr_standard","I94";
;
HDL_TAP"TRUE"
BODY_TYPE"PLUMBING"
CDS_LIB"mstr_standard";
"B \NAC \NWC"7;
"S \NAC"
BN"5"106;
%"TAP"
"6","(-2850,1100)","2","mstr_standard","I95";
;
HDL_TAP"TRUE"
BODY_TYPE"PLUMBING"
CDS_LIB"mstr_standard";
"B \NAC \NWC"7;
"S \NAC"
BN"3"104;
%"TAP"
"6","(-2850,1150)","2","mstr_standard","I96";
;
HDL_TAP"TRUE"
BODY_TYPE"PLUMBING"
CDS_LIB"mstr_standard";
"B \NAC \NWC"7;
"S \NAC"
BN"4"105;
%"TAP"
"6","(-2850,1250)","2","mstr_standard","I97";
;
HDL_TAP"TRUE"
BODY_TYPE"PLUMBING"
CDS_LIB"mstr_standard";
"B \NAC \NWC"7;
"S \NAC"
BN"6"107;
%"TAP"
"6","(-2850,1300)","2","mstr_standard","I98";
;
HDL_TAP"TRUE"
BODY_TYPE"PLUMBING"
CDS_LIB"mstr_standard";
"B \NAC \NWC"7;
"S \NAC"
BN"7"108;
%"TAP"
"6","(-2850,1450)","2","mstr_standard","I99";
;
HDL_TAP"TRUE"
BODY_TYPE"PLUMBING"
CDS_LIB"mstr_standard";
"B \NAC \NWC"8;
"S \NAC"
BN"1"95;
END.
